# SCM (Grand Teton) — schematic netlist excerpt (pin names and nets, part order shuffled) for the footprints in the layout excerpt that follows; sources: Cadence DE-HDL packaged netlist, KiCad conversion of 12092022_DA0F0TMDCD0_F0T_Management_Board_D_brd_V3_OCP.brd

R766  Q_RES  33.2 1% CHIP  pkg 0402LF  page 30 : A = UART_BMC_5_RXD_BUF1 ; B = UART_BMC_5_RXD_BUF1_SW

PU38  MPQ8633AGLEC807Z  MPQ8633AGLE-C807-Z IC  pkg QFN14_4X3  page 51
  BST  = SW_P5V_AUX_BST
  AGND  = GND
  CS  = P5V_AUX_CS
  MODE  = GND
  TRK_REF  = P5V_AUX_REF
  RGND  = GND
  FB  = P5V_AUX_FB
  EN  = EN_P5V_AUX
  PGOOD  = PWRGD_P5V_AUX_R
  VIN1  = SW_P5V_AUX_FLT
  PGND  = GND
  VCC  = P5V_AUX_VCC
  SW  = SW_P5V_AUX_SW
  VIN2  = SW_P5V_AUX_FLT

(kicad_pcb
	(version 20260206)
	(generator "pcbnew")
	(generator_version "10.0")
	(general
		(thickness 1.6)
		(legacy_teardrops no)
	)
	(paper "A4")
	(title_block
		(title "12092022_DA0F0TMDCD0_F0T_Management_Board_D_brd_V3_OCP.brd")
		(comment 1 "Grand Teton / footprints 628-629 of 1440")
	)
	(layers
		(0 "F.Cu" signal "TOP")
		(4 "In1.Cu" signal "GND")
		(6 "In2.Cu" signal "IN1")
		(8 "In3.Cu" signal "GND1")
		(10 "In4.Cu" signal "IN2")
		(12 "In5.Cu" signal "VCC")
		(14 "In6.Cu" signal "VCC1")
		(16 "In7.Cu" signal "IN3")
		(18 "In8.Cu" signal "GND2")
		(20 "In9.Cu" signal "IN4")
		(22 "In10.Cu" signal "GND3")
		(2 "B.Cu" signal "BOTTOM")
		(9 "F.Adhes" user "F.Adhesive")
		(11 "B.Adhes" user "B.Adhesive")
		(13 "F.Paste" user "Package Geometry/Pastemask Top")
		(15 "B.Paste" user "Package Geometry/Pastemask Bottom")
		(5 "F.SilkS" user "Ref Des/Silkscreen Top")
		(7 "B.SilkS" user "Ref Des/Silkscreen Bottom")
		(1 "F.Mask" user "Board Geometry/Soldermask Top")
		(3 "B.Mask" user "Board Geometry/Soldermask Bottom")
		(17 "Dwgs.User" user "User.Drawings")
		(19 "Cmts.User" user "User.Comments")
		(21 "Eco1.User" user "User.Eco1")
		(23 "Eco2.User" user "User.Eco2")
		(25 "Edge.Cuts" user "Board Geometry/Outline")
		(27 "Margin" user)
		(31 "F.CrtYd" user "Package Geometry/Place Bound Top")
		(29 "B.CrtYd" user "Package Geometry/Place Bound Bottom")
		(35 "F.Fab" user "Ref Des/Assembly Top")
		(33 "B.Fab" user "Ref Des/Assembly Bottom")
	)
	(footprint ""
		(layer "F.Cu")
		(at 19.1516 -58.7756 90)
		(property "Reference" "R766"
			(at 0 0 90)
			(layer "F.SilkS")
			(hide yes)
			(effects
				(font
					(size 1.27 1.27)
				)
			)
		)
		(property "Value" ""
			(at 0 0 90)
			(layer "F.Fab")
			(effects
				(font
					(size 1.27 1.27)
				)
			)
		)
		(duplicate_pad_numbers_are_jumpers no)
		(fp_line
			(start 0.7874 -0.4064)
			(end 0.7874 0.4064)
			(stroke
				(width 0.1524)
				(type default)
			)
			(layer "F.SilkS")
		)
		(fp_line
			(start -0.7874 -0.4064)
			(end 0.7874 -0.4064)
			(stroke
				(width 0.1524)
				(type default)
			)
			(layer "F.SilkS")
		)
		(fp_line
			(start 0.7874 0.4064)
			(end -0.7874 0.4064)
			(stroke
				(width 0.1524)
				(type default)
			)
			(layer "F.SilkS")
		)
		(fp_line
			(start -0.7874 0.4064)
			(end -0.7874 -0.4064)
			(stroke
				(width 0.1524)
				(type default)
			)
			(layer "F.SilkS")
		)
		(fp_line
			(start -0.12065 -0.305054)
			(end -0.12065 -0.2794)
			(stroke
				(width 0.1)
				(type default)
			)
			(layer "F.Fab")
		)
		(fp_line
			(start -0.67945 -0.305054)
			(end -0.12065 -0.305054)
			(stroke
				(width 0.1)
				(type default)
			)
			(layer "F.Fab")
		)
		(fp_line
			(start 0.67945 -0.3048)
			(end 0.67945 0.3048)
			(stroke
				(width 0.1)
				(type default)
			)
			(layer "F.Fab")
		)
		(fp_line
			(start 0.12065 -0.3048)
			(end 0.67945 -0.3048)
			(stroke
				(width 0.1)
				(type default)
			)
			(layer "F.Fab")
		)
		(fp_line
			(start 0.12065 -0.2794)
			(end 0.12065 -0.3048)
			(stroke
				(width 0.1)
				(type default)
			)
			(layer "F.Fab")
		)
		(fp_line
			(start -0.12065 -0.2794)
			(end 0.12065 -0.2794)
			(stroke
				(width 0.1)
				(type default)
			)
			(layer "F.Fab")
		)
		(fp_line
			(start 0.120396 0.2794)
			(end -0.12065 0.2794)
			(stroke
				(width 0.1)
				(type default)
			)
			(layer "F.Fab")
		)
		(fp_line
			(start -0.12065 0.2794)
			(end -0.12065 0.3048)
			(stroke
				(width 0.1)
				(type default)
			)
			(layer "F.Fab")
		)
		(fp_line
			(start 0.67945 0.3048)
			(end 0.120396 0.3048)
			(stroke
				(width 0.1)
				(type default)
			)
			(layer "F.Fab")
		)
		(fp_line
			(start 0.120396 0.3048)
			(end 0.120396 0.2794)
			(stroke
				(width 0.1)
				(type default)
			)
			(layer "F.Fab")
		)
		(fp_line
			(start -0.12065 0.3048)
			(end -0.67945 0.3048)
			(stroke
				(width 0.1)
				(type default)
			)
			(layer "F.Fab")
		)
		(fp_line
			(start -0.67945 0.3048)
			(end -0.67945 -0.305054)
			(stroke
				(width 0.1)
				(type default)
			)
			(layer "F.Fab")
		)
		(pad "1" smd circle
			(at -0.40005 0 90)
			(size 0 0)
			(layers "F.Cu" "F.Mask" "F.Paste")
			(net "UART_BMC_5_RXD_BUF1")
		)
		(pad "2" smd circle
			(at 0.40005 0 90)
			(size 0 0)
			(layers "F.Cu" "F.Mask" "F.Paste")
			(net "UART_BMC_5_RXD_BUF1_SW")
		)
	)
	(footprint ""
		(layer "F.Cu")
		(at 7.059676 -49.979834 180)
		(property "Reference" "PU38"
			(at 3.122168 -3.362452 0)
			(unlocked yes)
			(layer "F.SilkS")
			(effects
				(font
					(size 0.7874 0.5842)
					(thickness 0.1524)
				)
				(justify left)
			)
		)
		(property "Value" ""
			(at 0 0 180)
			(layer "F.Fab")
			(effects
				(font
					(size 1.27 1.27)
				)
			)
		)
		(duplicate_pad_numbers_are_jumpers no)
		(fp_line
			(start 1.549908 2.050034)
			(end 1.549908 1.9304)
			(stroke
				(width 0.1524)
				(type default)
			)
			(layer "F.SilkS")
		)
		(fp_line
			(start 1.549908 -1.9812)
			(end 1.549908 -2.050034)
			(stroke
				(width 0.1524)
				(type default)
			)
			(layer "F.SilkS")
		)
		(fp_line
			(start 1.549908 -2.050034)
			(end 0.5842 -2.050034)
			(stroke
				(width 0.1524)
				(type default)
			)
			(layer "F.SilkS")
		)
		(fp_line
			(start 0 2.050034)
			(end 1.549908 2.050034)
			(stroke
				(width 0.1524)
				(type default)
			)
			(layer "F.SilkS")
		)
		(fp_line
			(start -0.5842 -2.050034)
			(end -1.549908 -2.050034)
			(stroke
				(width 0.1524)
				(type default)
			)
			(layer "F.SilkS")
		)
		(fp_line
			(start -1.549908 2.050034)
			(end -0.5842 2.050034)
			(stroke
				(width 0.1524)
				(type default)
			)
			(layer "F.SilkS")
		)
		(fp_line
			(start -1.549908 1.9812)
			(end -1.549908 2.050034)
			(stroke
				(width 0.1524)
				(type default)
			)
			(layer "F.SilkS")
		)
		(fp_line
			(start -1.549908 -2.050034)
			(end -1.549908 -1.9812)
			(stroke
				(width 0.1524)
				(type default)
			)
			(layer "F.SilkS")
		)
		(fp_poly
			(pts
				(xy -2.9464 -2.208022) (xy -2.9464 -1.192022) (xy -1.9304 -1.700022)
			)
			(stroke
				(width 0)
				(type default)
			)
			(fill yes)
			(layer "F.SilkS")
		)
		(fp_line
			(start 1.549908 2.050034)
			(end 1.549908 -2.050034)
			(stroke
				(width 0.1)
				(type default)
			)
			(layer "F.Fab")
		)
		(fp_line
			(start 1.549908 -2.050034)
			(end -1.549908 -2.050034)
			(stroke
				(width 0.1)
				(type default)
			)
			(layer "F.Fab")
		)
		(fp_line
			(start -1.549908 2.050034)
			(end 1.549908 2.050034)
			(stroke
				(width 0.1)
				(type default)
			)
			(layer "F.Fab")
		)
		(fp_line
			(start -1.549908 -2.050034)
			(end -1.549908 2.050034)
			(stroke
				(width 0.1)
				(type default)
			)
			(layer "F.Fab")
		)
		(fp_poly
			(pts
				(xy -2.9464 -2.208022) (xy -2.9464 -1.192022) (xy -1.9304 -1.700022)
			)
			(stroke
				(width 0)
				(type default)
			)
			(fill yes)
			(layer "F.Fab")
		)
		(pad "1" smd circle
			(at -1.35001 -1.700022 180)
			(size 0 0)
			(layers "F.Cu" "F.Mask" "F.Paste")
			(net "SW_P5V_AUX_BST")
		)
		(pad "2" smd rect
			(at -1.400048 -1.199896 270)
			(size 0.1778 0.8128)
			(layers "F.Cu" "F.Mask" "F.Paste")
			(net "GND")
		)
		(pad "3" smd rect
			(at -1.400048 -0.8001 270)
			(size 0.1778 0.8128)
			(layers "F.Cu" "F.Mask" "F.Paste")
			(net "P5V_AUX_CS")
		)
		(pad "4" smd rect
			(at -1.400048 -0.40005 270)
			(size 0.1778 0.8128)
			(layers "F.Cu" "F.Mask" "F.Paste")
			(net "GND")
		)
		(pad "5" smd rect
			(at -1.400048 0 270)
			(size 0.1778 0.8128)
			(layers "F.Cu" "F.Mask" "F.Paste")
			(net "P5V_AUX_REF")
		)
		(pad "6" smd rect
			(at -1.400048 0.40005 270)
			(size 0.1778 0.8128)
			(layers "F.Cu" "F.Mask" "F.Paste")
			(net "GND")
		)
		(pad "7" smd rect
			(at -1.400048 0.8001 270)
			(size 0.1778 0.8128)
			(layers "F.Cu" "F.Mask" "F.Paste")
			(net "P5V_AUX_FB")
		)
		(pad "8" smd rect
			(at -1.400048 1.199896 270)
			(size 0.1778 0.8128)
			(layers "F.Cu" "F.Mask" "F.Paste")
			(net "EN_P5V_AUX")
		)
		(pad "9" smd rect
			(at -1.400048 1.700022 270)
			(size 0.3048 0.8128)
			(layers "F.Cu" "F.Mask" "F.Paste")
			(net "PWRGD_P5V_AUX_R")
		)
		(pad "10" smd rect
			(at -0.299974 1.299972 180)
			(size 0.3048 2.0066)
			(layers "F.Cu" "F.Mask" "F.Paste")
			(net "SW_P5V_AUX_FLT")
		)
		(pad "11_18" smd circle
			(at 1.175004 0.275082 180)
			(size 0 0)
			(layers "F.Cu" "F.Mask" "F.Paste")
			(net "GND")
		)
		(pad "19" smd rect
			(at 1.400048 -1.700022 90)
			(size 0.3048 0.8128)
			(layers "F.Cu" "F.Mask" "F.Paste")
			(net "P5V_AUX_VCC")
		)
		(pad "20" smd rect
			(at 0.299974 -1.299972 180)
			(size 0.3048 2.0066)
			(layers "F.Cu" "F.Mask" "F.Paste")
			(net "SW_P5V_AUX_SW")
		)
		(pad "21" smd rect
			(at -0.299974 -1.299972 180)
			(size 0.3048 2.0066)
			(layers "F.Cu" "F.Mask" "F.Paste")
			(net "SW_P5V_AUX_FLT")
		)
	)
)
